# BASEBOARD_FAB2 (Tioga Pass) — schematic netlist excerpt (pin names and nets, part order shuffled) for the footprints in the layout excerpt that follows; sources: Cadence DE-HDL packaged netlist, KiCad conversion of Wiwynn_Tioga_Pass_MB.brd

J1C1  DM-FCI-CONN76-8R-GP-U-01  pkg CONN-G4  page 182
  PCIE_RX_DP0  = P3E_CPU1_PE3_MP_RXN<8>
  GND1  = GND
  PCIE_RX_DP6  = P3E_CPU1_PE3_MP_RXP<14>
  FAN_TACH3  = GND
  MNG_TX_DP  = TP_IOA5
  \pmbus_alert#\  = GND
  PCIE_TX_DP3  = P3E_CPU1_PE3_MP_C_TXN<11>
  GND2  = GND
  PCIE_RX_DN0  = P3E_CPU1_PE3_MP_RXP<8>
  PCIE_RX_DP3  = P3E_CPU1_PE3_MP_RXN<11>
  PCIE_RX_DN6  = P3E_CPU1_PE3_MP_RXN<14>
  FAN_TACH2  = TP_FM_WAKE_N
  MNG_TX_DN  = IRQ_BOARD_BMC_ALERT_N
  PMBUS_DATA  = SMB_PEHPCPU1_STBY_LVC3_SDA
  PCIE_TX_DN3  = P3E_CPU1_PE3_MP_C_TXP<11>
  PCIE_TX_DP0  = P3E_CPU1_PE3_MP_C_TXN<8>
  GND3  = GND
  PCIE_RX_DN3  = P3E_CPU1_PE3_MP_RXP<11>
  GND4  = GND
  FAN_TACH1  = FM_BB_BMC_MP_GPIO
  GND5  = GND
  PMBUS_CLK  = SMB_PEHPCPU1_STBY_LVC3_SCL
  GND6  = GND
  PCIE_TX_DN0  = P3E_CPU1_PE3_MP_C_TXP<8>
  PCIE_RX_DP1  = P3E_CPU1_PE3_MP_RXN<9>
  GND7  = GND
  PCIE_RX_DP7  = P3E_CPU1_PE3_MP_RXN<15>
  FAN_TACH0  = GND
  MNG_RX_DP  = SMB_LAN_STBY_LVC3_SDA
  GND8  = GND
  PCIE_TX_DP4  = P3E_CPU1_PE3_MP_C_TXN<12>
  GND9  = GND
  PCIE_RX_DN1  = P3E_CPU1_PE3_MP_RXP<9>
  PCIE_RX_DP4  = P3E_CPU1_PE3_MP_RXN<12>
  PCIE_RX_DN7  = P3E_CPU1_PE3_MP_RXP<15>
  \mated_in#\  = TP_IOE4
  MNG_RX_DN  = SMB_LAN_STBY_LVC3_SCL
  PCIE_TX_DP6  = P3E_CPU1_PE3_MP_C_TXN<14>
  PCIE_TX_DN4  = P3E_CPU1_PE3_MP_C_TXP<12>
  PCIE_TX_DP1  = P3E_CPU1_PE3_MP_C_TXN<9>
  GND10  = GND
  PCIE_RX_DN4  = P3E_CPU1_PE3_MP_RXP<12>
  GND11  = GND
  FAN_PWM0  = TP_IOF4
  MB_SLOT_ID0  = GND
  PCIE_TX_DN6  = P3E_CPU1_PE3_MP_C_TXP<14>
  GND12  = GND
  PCIE_TX_DN1  = P3E_CPU1_PE3_MP_C_TXP<9>
  PCIE_RX_DP2  = P3E_CPU1_PE3_MP_RXP<10>
  GND13  = GND
  COM_TX  = TP_IOG3
  GND14  = GND
  MB_SLOT_ID1  = FM_XRC_PRESENT_N
  GND15  = GND
  PCIE_TX_DP5  = P3E_CPU1_PE3_MP_C_TXN<13>
  GND16  = GND
  PCIE_RX_DN2  = P3E_CPU1_PE3_MP_RXN<10>
  PCIE_RX_DP5  = P3E_CPU1_PE3_MP_RXP<13>
  COM_RX  = TP_IOH3
  PCIE_CLK_100M_DP  = TP_IOH4
  MB_SLOT_ID2  = FM_XRC_READY_N
  PCIE_TX_DP7  = P3E_CPU1_PE3_MP_C_TXN<15>
  PCIE_TX_DN5  = P3E_CPU1_PE3_MP_C_TXP<13>
  PCIE_TX_DP2  = P3E_CPU1_PE3_MP_C_TXP<10>
  GND17  = GND
  PCIE_RX_DN5  = P3E_CPU1_PE3_MP_RXN<13>
  \mb_on#\  = GND
  PCIE_CLK_100M_DN  = TP_IOI4
  \pcie_perst#\  = GND
  PCIE_TX_DN7  = P3E_CPU1_PE3_MP_C_TXP<15>
  GND18  = GND
  PCIE_TX_DN2  = P3E_CPU1_PE3_MP_C_TXN<10>
  J2  = GND
  J4  = GND
  J6  = GND
  J8  = GND

(kicad_pcb
	(version 20260206)
	(generator "pcbnew")
	(generator_version "10.0")
	(general
		(thickness 1.6)
		(legacy_teardrops no)
	)
	(paper "A4")
	(title_block
		(title "Wiwynn_Tioga_Pass_MB.brd")
		(comment 1 "Tioga Pass / footprint 1357 of 4770 (J1C1), pads 30-58 of 76")
	)
	(layers
		(0 "F.Cu" signal "TOP")
		(4 "In1.Cu" signal "L2GND")
		(6 "In2.Cu" signal "L3")
		(8 "In3.Cu" signal "L4GND")
		(10 "In4.Cu" signal "L5")
		(12 "In5.Cu" signal "L6GND")
		(14 "In6.Cu" signal "L7VCC")
		(16 "In7.Cu" signal "L8VCC")
		(18 "In8.Cu" signal "L9GND")
		(20 "In9.Cu" signal "L10")
		(22 "In10.Cu" signal "L11GND")
		(24 "In11.Cu" signal "L12")
		(26 "In12.Cu" signal "L13GND")
		(2 "B.Cu" signal "BOTTOM")
		(9 "F.Adhes" user "F.Adhesive")
		(11 "B.Adhes" user "B.Adhesive")
		(13 "F.Paste" user "Package Geometry/Pastemask Top")
		(15 "B.Paste" user "Package Geometry/Pastemask Bottom")
		(5 "F.SilkS" user "Ref Des/Silkscreen Top")
		(7 "B.SilkS" user "Ref Des/Silkscreen Bottom")
		(1 "F.Mask" user "Board Geometry/Soldermask Top")
		(3 "B.Mask" user "Board Geometry/Soldermask Bottom")
		(17 "Dwgs.User" user "User.Drawings")
		(19 "Cmts.User" user "User.Comments")
		(21 "Eco1.User" user "User.Eco1")
		(23 "Eco2.User" user "User.Eco2")
		(25 "Edge.Cuts" user "Board Geometry/Outline")
		(27 "Margin" user)
		(31 "F.CrtYd" user "Package Geometry/Place Bound Top")
		(29 "B.CrtYd" user "Package Geometry/Place Bound Bottom")
		(35 "F.Fab" user "Ref Des/Assembly Top")
		(33 "B.Fab" user "Ref Des/Assembly Bottom")
	)
	(footprint ""
		(layer "F.Cu")
		(at 2.29997 -97.769934 -90)
		(property "Reference" "J1C1"
			(at 0 0 270)
			(layer "F.SilkS")
			(hide yes)
			(effects
				(font
					(size 1.27 1.27)
				)
			)
		)
		(property "Value" "*"
			(at -20.8026 -3.4036 270)
			(unlocked yes)
			(layer "F.Fab")
			(hide yes)
			(effects
				(font
					(size 1.27 1.016)
					(thickness 0.1524)
				)
			)
		)
		(property "Device Type" "DM-FCI-CONN76-8R-GP-U-01_CONN-A"
			(at -20.8026 -4.9276 270)
			(unlocked yes)
			(layer "F.Fab")
			(hide yes)
			(effects
				(font
					(size 1.27 1.016)
					(thickness 0.1524)
				)
			)
		)
		(duplicate_pad_numbers_are_jumpers no)
		(pad "D6" thru_hole circle
			(at 2.999994 2.100072 270)
			(size 0.8636 0.8636)
			(drill 0.499872)
			(layers "*.Cu" "*.Mask")
			(remove_unused_layers no)
			(net "GND")
			(clearance 0.1778)
			(thermal_gap 0.1778)
		)
		(pad "D7" thru_hole circle
			(at 4.99999 1.999996 270)
			(size 0.8128 0.8128)
			(drill 0.399796)
			(layers "*.Cu" "*.Mask")
			(remove_unused_layers no)
			(net "P3E_CPU1_PE3_MP_C_TXN<12>")
			(clearance 0.2921)
			(thermal_gap 0.2921)
		)
		(pad "D8" thru_hole circle
			(at 6.999986 2.100072 270)
			(size 0.8636 0.8636)
			(drill 0.499872)
			(layers "*.Cu" "*.Mask")
			(remove_unused_layers no)
			(net "GND")
			(clearance 0.1778)
			(thermal_gap 0.1778)
		)
		(pad "E1" thru_hole circle
			(at -6.999986 0.599948 270)
			(size 0.8128 0.8128)
			(drill 0.399796)
			(layers "*.Cu" "*.Mask")
			(remove_unused_layers no)
			(net "P3E_CPU1_PE3_MP_RXP<9>")
			(clearance 0.2921)
			(thermal_gap 0.2921)
		)
		(pad "E2" thru_hole circle
			(at -4.99999 0.700024 270)
			(size 0.8128 0.8128)
			(drill 0.399796)
			(layers "*.Cu" "*.Mask")
			(remove_unused_layers no)
			(net "P3E_CPU1_PE3_MP_RXN<12>")
			(clearance 0.2921)
			(thermal_gap 0.2921)
		)
		(pad "E3" thru_hole circle
			(at -2.999994 0.599948 270)
			(size 0.8128 0.8128)
			(drill 0.399796)
			(layers "*.Cu" "*.Mask")
			(remove_unused_layers no)
			(net "P3E_CPU1_PE3_MP_RXP<15>")
			(clearance 0.2921)
			(thermal_gap 0.2921)
		)
		(pad "E4" thru_hole circle
			(at -0.999998 0.700024 270)
			(size 0.8128 0.8128)
			(drill 0.399796)
			(layers "*.Cu" "*.Mask")
			(remove_unused_layers no)
			(net "TP_IOE4")
			(clearance 0.1524)
			(thermal_gap 0.1524)
		)
		(pad "E5" thru_hole circle
			(at 0.999998 0.599948 270)
			(size 0.8128 0.8128)
			(drill 0.399796)
			(layers "*.Cu" "*.Mask")
			(remove_unused_layers no)
			(net "SMB_LAN_STBY_LVC3_SCL")
			(clearance 0.2921)
			(thermal_gap 0.2921)
		)
		(pad "E6" thru_hole circle
			(at 2.999994 0.700024 270)
			(size 0.8128 0.8128)
			(drill 0.399796)
			(layers "*.Cu" "*.Mask")
			(remove_unused_layers no)
			(net "P3E_CPU1_PE3_MP_C_TXN<14>")
			(clearance 0.2921)
			(thermal_gap 0.2921)
		)
		(pad "E7" thru_hole circle
			(at 4.99999 0.599948 270)
			(size 0.8128 0.8128)
			(drill 0.399796)
			(layers "*.Cu" "*.Mask")
			(remove_unused_layers no)
			(net "P3E_CPU1_PE3_MP_C_TXP<12>")
			(clearance 0.2921)
			(thermal_gap 0.2921)
		)
		(pad "E8" thru_hole circle
			(at 6.999986 0.700024 270)
			(size 0.8128 0.8128)
			(drill 0.399796)
			(layers "*.Cu" "*.Mask")
			(remove_unused_layers no)
			(net "P3E_CPU1_PE3_MP_C_TXN<9>")
			(clearance 0.2921)
			(thermal_gap 0.2921)
		)
		(pad "F1" thru_hole circle
			(at -6.999986 -0.8001 270)
			(size 0.8636 0.8636)
			(drill 0.499872)
			(layers "*.Cu" "*.Mask")
			(remove_unused_layers no)
			(net "GND")
			(clearance 0.1778)
			(thermal_gap 0.1778)
		)
		(pad "F2" thru_hole circle
			(at -4.99999 -0.700024 270)
			(size 0.8128 0.8128)
			(drill 0.399796)
			(layers "*.Cu" "*.Mask")
			(remove_unused_layers no)
			(net "P3E_CPU1_PE3_MP_RXP<12>")
			(clearance 0.2921)
			(thermal_gap 0.2921)
		)
		(pad "F3" thru_hole circle
			(at -2.999994 -0.8001 270)
			(size 0.8636 0.8636)
			(drill 0.499872)
			(layers "*.Cu" "*.Mask")
			(remove_unused_layers no)
			(net "GND")
			(clearance 0.1778)
			(thermal_gap 0.1778)
		)
		(pad "F4" thru_hole circle
			(at -0.999998 -0.700024 270)
			(size 0.8128 0.8128)
			(drill 0.399796)
			(layers "*.Cu" "*.Mask")
			(remove_unused_layers no)
			(net "TP_IOF4")
			(clearance 0.1524)
			(thermal_gap 0.1524)
		)
		(pad "F5" thru_hole circle
			(at 0.999998 -0.8001 270)
			(size 0.8636 0.8636)
			(drill 0.499872)
			(layers "*.Cu" "*.Mask")
			(remove_unused_layers no)
			(net "GND")
			(clearance 0.1778)
			(thermal_gap 0.1778)
		)
		(pad "F6" thru_hole circle
			(at 2.999994 -0.700024 270)
			(size 0.8128 0.8128)
			(drill 0.399796)
			(layers "*.Cu" "*.Mask")
			(remove_unused_layers no)
			(net "P3E_CPU1_PE3_MP_C_TXP<14>")
			(clearance 0.2921)
			(thermal_gap 0.2921)
		)
		(pad "F7" thru_hole circle
			(at 4.99999 -0.8001 270)
			(size 0.8636 0.8636)
			(drill 0.499872)
			(layers "*.Cu" "*.Mask")
			(remove_unused_layers no)
			(net "GND")
			(clearance 0.1778)
			(thermal_gap 0.1778)
		)
		(pad "F8" thru_hole circle
			(at 6.999986 -0.700024 270)
			(size 0.8128 0.8128)
			(drill 0.399796)
			(layers "*.Cu" "*.Mask")
			(remove_unused_layers no)
			(net "P3E_CPU1_PE3_MP_C_TXP<9>")
			(clearance 0.2921)
			(thermal_gap 0.2921)
		)
		(pad "G1" thru_hole circle
			(at -6.999986 -2.199894 270)
			(size 0.8128 0.8128)
			(drill 0.399796)
			(layers "*.Cu" "*.Mask")
			(remove_unused_layers no)
			(net "P3E_CPU1_PE3_MP_RXP<10>")
			(clearance 0.2921)
			(thermal_gap 0.2921)
		)
		(pad "G2" thru_hole circle
			(at -4.99999 -2.100072 270)
			(size 0.8636 0.8636)
			(drill 0.499872)
			(layers "*.Cu" "*.Mask")
			(remove_unused_layers no)
			(net "GND")
			(clearance 0.1778)
			(thermal_gap 0.1778)
		)
		(pad "G3" thru_hole circle
			(at -2.999994 -2.199894 270)
			(size 0.8128 0.8128)
			(drill 0.399796)
			(layers "*.Cu" "*.Mask")
			(remove_unused_layers no)
			(net "TP_IOG3")
			(clearance 0.1524)
			(thermal_gap 0.1524)
		)
		(pad "G4" thru_hole circle
			(at -0.999998 -2.100072 270)
			(size 0.8636 0.8636)
			(drill 0.499872)
			(layers "*.Cu" "*.Mask")
			(remove_unused_layers no)
			(net "GND")
			(clearance 0.1778)
			(thermal_gap 0.1778)
		)
		(pad "G5" thru_hole circle
			(at 0.999998 -2.199894 270)
			(size 0.8128 0.8128)
			(drill 0.399796)
			(layers "*.Cu" "*.Mask")
			(remove_unused_layers no)
			(net "FM_XRC_PRESENT_N")
			(clearance 0.1524)
			(thermal_gap 0.1524)
		)
		(pad "G6" thru_hole circle
			(at 2.999994 -2.100072 270)
			(size 0.8636 0.8636)
			(drill 0.499872)
			(layers "*.Cu" "*.Mask")
			(remove_unused_layers no)
			(net "GND")
			(clearance 0.1778)
			(thermal_gap 0.1778)
		)
		(pad "G7" thru_hole circle
			(at 4.99999 -2.199894 270)
			(size 0.8128 0.8128)
			(drill 0.399796)
			(layers "*.Cu" "*.Mask")
			(remove_unused_layers no)
			(net "P3E_CPU1_PE3_MP_C_TXN<13>")
			(clearance 0.2921)
			(thermal_gap 0.2921)
		)
		(pad "G8" thru_hole circle
			(at 6.999986 -2.100072 270)
			(size 0.8636 0.8636)
			(drill 0.499872)
			(layers "*.Cu" "*.Mask")
			(remove_unused_layers no)
			(net "GND")
			(clearance 0.1778)
			(thermal_gap 0.1778)
		)
		(pad "H1" thru_hole circle
			(at -6.999986 -3.599942 270)
			(size 0.8128 0.8128)
			(drill 0.399796)
			(layers "*.Cu" "*.Mask")
			(remove_unused_layers no)
			(net "P3E_CPU1_PE3_MP_RXN<10>")
			(clearance 0.2921)
			(thermal_gap 0.2921)
		)
		(pad "H2" thru_hole circle
			(at -4.99999 -3.50012 270)
			(size 0.8128 0.8128)
			(drill 0.399796)
			(layers "*.Cu" "*.Mask")
			(remove_unused_layers no)
			(net "P3E_CPU1_PE3_MP_RXP<13>")
			(clearance 0.2921)
			(thermal_gap 0.2921)
		)
	)
)
